(kicad_pcb
	(version 20260206)
	(generator "pcbnew")
	(generator_version "10.0")
	(general
		(thickness 1.6)
		(legacy_teardrops no)
	)
	(paper "A4")
	(title_block
		(title "Bryce Canyon_R.DPB_16317-1_OCP.brd")
		(comment 1 "Bryce Canyon / footprints 1276-1282 of 2099")
	)
	(layers
		(0 "F.Cu" signal "TOP")
		(4 "In1.Cu" signal "L2GND")
		(6 "In2.Cu" signal "L3")
		(8 "In3.Cu" signal "L4VCC")
		(10 "In4.Cu" signal "L5VCC")
		(12 "In5.Cu" signal "L6")
		(14 "In6.Cu" signal "L7GND")
		(2 "B.Cu" signal "BOTTOM")
		(9 "F.Adhes" user "F.Adhesive")
		(11 "B.Adhes" user "B.Adhesive")
		(13 "F.Paste" user "Package Geometry/Pastemask Top")
		(15 "B.Paste" user "Package Geometry/Pastemask Bottom")
		(5 "F.SilkS" user "Ref Des/Silkscreen Top")
		(7 "B.SilkS" user "Ref Des/Silkscreen Bottom")
		(1 "F.Mask" user "Board Geometry/Soldermask Top")
		(3 "B.Mask" user "Board Geometry/Soldermask Bottom")
		(17 "Dwgs.User" user "User.Drawings")
		(19 "Cmts.User" user "User.Comments")
		(21 "Eco1.User" user "User.Eco1")
		(23 "Eco2.User" user "User.Eco2")
		(25 "Edge.Cuts" user "Board Geometry/Outline")
		(27 "Margin" user)
		(31 "F.CrtYd" user "Package Geometry/Place Bound Top")
		(29 "B.CrtYd" user "Package Geometry/Place Bound Bottom")
		(35 "F.Fab" user "Ref Des/Assembly Top")
		(33 "B.Fab" user "Ref Des/Assembly Bottom")
	)
	(footprint ""
		(layer "F.Cu")
		(at 95.563436 -15.219426 90)
		(property "Reference" "C366"
			(at 0 0 90)
			(layer "F.SilkS")
			(hide yes)
			(effects
				(font
					(size 1.27 1.27)
				)
			)
		)
		(property "Value" "SCD01U16V1KX-GP"
			(at -2.8321 -1.7399 90)
			(unlocked yes)
			(layer "F.Fab")
			(hide yes)
			(effects
				(font
					(size 1.016 1.016)
					(thickness 0.1524)
				)
			)
		)
		(property "Device Type" "C0201H13"
			(at -2.8321 -3.2639 90)
			(unlocked yes)
			(layer "F.Fab")
			(hide yes)
			(effects
				(font
					(size 1.016 1.016)
					(thickness 0.1524)
				)
			)
		)
		(duplicate_pad_numbers_are_jumpers no)
		(fp_rect
			(start -0.2794 0.6477)
			(end 0.2794 -0.6477)
			(stroke
				(width 0)
				(type default)
			)
			(fill no)
			(layer "F.CrtYd")
		)
		(fp_rect
			(start -0.2794 0.6477)
			(end 0.2794 -0.6477)
			(stroke
				(width 0)
				(type default)
			)
			(fill no)
			(layer "F.Fab")
		)
		(pad "1" smd custom
			(at 0 -0.2794 90)
			(size 0.0762 0.0762)
			(layers "F.Cu" "F.Mask" "F.Paste")
			(net "SAS_HDD_RX_N26")
			(options
				(clearance outline)
				(anchor circle)
			)
			(primitives
				(gr_poly
					(pts
						(arc
							(start 0.1524 -0.127)
							(mid 0.137521 -0.162921)
							(end 0.1016 -0.1778)
						)
						(arc
							(start -0.1016 -0.1778)
							(mid -0.137521 -0.162921)
							(end -0.1524 -0.127)
						)
						(arc
							(start -0.1524 0.127)
							(mid -0.137521 0.162921)
							(end -0.1016 0.1778)
						)
						(arc
							(start 0.1016 0.1778)
							(mid 0.137521 0.162921)
							(end 0.1524 0.127)
						)
					)
					(width 0)
					(fill yes)
				)
			)
		)
		(pad "2" smd custom
			(at 0 0.2794 90)
			(size 0.0762 0.0762)
			(layers "F.Cu" "F.Mask" "F.Paste")
			(net "PHY_SCC_B_TO_DRV_B_26_DN")
			(options
				(clearance outline)
				(anchor circle)
			)
			(primitives
				(gr_poly
					(pts
						(arc
							(start 0.1524 -0.127)
							(mid 0.137521 -0.162921)
							(end 0.1016 -0.1778)
						)
						(arc
							(start -0.1016 -0.1778)
							(mid -0.137521 -0.162921)
							(end -0.1524 -0.127)
						)
						(arc
							(start -0.1524 0.127)
							(mid -0.137521 0.162921)
							(end -0.1016 0.1778)
						)
						(arc
							(start 0.1016 0.1778)
							(mid 0.137521 0.162921)
							(end 0.1524 0.127)
						)
					)
					(width 0)
					(fill yes)
				)
			)
		)
	)
	(footprint ""
		(layer "F.Cu")
		(at 333.629 -357.2256)
		(property "Reference" "D47"
			(at 0 0 0)
			(layer "F.SilkS")
			(hide yes)
			(effects
				(font
					(size 1.27 1.27)
				)
			)
		)
		(property "Value" "RB551V30-GP"
			(at 0 -6.7818 0)
			(unlocked yes)
			(layer "F.Fab")
			(hide yes)
			(effects
				(font
					(size 1.016 1.016)
					(thickness 0.1524)
				)
			)
		)
		(property "Device Type" "SOD323AKH38"
			(at 0 -8.6868 0)
			(unlocked yes)
			(layer "F.Fab")
			(hide yes)
			(effects
				(font
					(size 1.016 1.016)
					(thickness 0.1524)
				)
			)
		)
		(duplicate_pad_numbers_are_jumpers no)
		(fp_line
			(start -0.889 -1.9304)
			(end 0.889 -1.9304)
			(stroke
				(width 0.1524)
				(type default)
			)
			(layer "F.SilkS")
		)
		(fp_line
			(start -0.889 2.159)
			(end -0.889 -1.9304)
			(stroke
				(width 0.1524)
				(type default)
			)
			(layer "F.SilkS")
		)
		(fp_line
			(start 0.762 2.0574)
			(end -0.762 2.0574)
			(stroke
				(width 0.508)
				(type default)
			)
			(layer "F.SilkS")
		)
		(fp_line
			(start 0.889 -1.9304)
			(end 0.889 2.159)
			(stroke
				(width 0.1524)
				(type default)
			)
			(layer "F.SilkS")
		)
		(fp_line
			(start 0.889 2.159)
			(end -0.889 2.159)
			(stroke
				(width 0.1524)
				(type default)
			)
			(layer "F.SilkS")
		)
		(fp_rect
			(start -1.016 2.3114)
			(end 1.016 -2.0066)
			(stroke
				(width 0)
				(type default)
			)
			(fill no)
			(layer "F.CrtYd")
		)
		(fp_poly
			(pts
				(xy -1.016 -2.0066) (xy 1.016 -2.0066) (xy 1.016 2.3114) (xy -1.016 2.3114)
			)
			(stroke
				(width 0)
				(type default)
			)
			(fill no)
			(layer "F.Fab")
		)
		(pad "A" smd rect
			(at 0 -1.143)
			(size 0.5588 1.016)
			(layers "F.Cu" "F.Mask" "F.Paste")
			(net "GATE_FAN2")
		)
		(pad "K" smd rect
			(at 0 1.143)
			(size 0.5588 1.016)
			(layers "F.Cu" "F.Mask" "F.Paste")
			(net "GATE_FAN2_R")
		)
	)
	(footprint ""
		(layer "F.Cu")
		(at 17.800066 -180.399944)
		(property "Reference" "LED1"
			(at 0 0 0)
			(layer "F.SilkS")
			(hide yes)
			(effects
				(font
					(size 1.27 1.27)
				)
			)
		)
		(property "Value" "LED-BY-19-GP"
			(at -2.132076 1.414018 0)
			(unlocked yes)
			(layer "F.Fab")
			(hide yes)
			(effects
				(font
					(size 1.016 1.016)
					(thickness 0.1524)
				)
			)
		)
		(property "Device Type" "LED-1615-4PH26"
			(at -2.132076 -0.109982 0)
			(unlocked yes)
			(layer "F.Fab")
			(hide yes)
			(effects
				(font
					(size 1.016 1.016)
					(thickness 0.1524)
				)
			)
		)
		(duplicate_pad_numbers_are_jumpers no)
		(fp_line
			(start -1.2954 0.254)
			(end -1.2954 1.6002)
			(stroke
				(width 0.508)
				(type default)
			)
			(layer "F.SilkS")
		)
		(fp_line
			(start -1.2954 1.6002)
			(end 1.2954 1.6002)
			(stroke
				(width 0.508)
				(type default)
			)
			(layer "F.SilkS")
		)
		(fp_line
			(start -1.1176 -1.4224)
			(end 1.1176 -1.4224)
			(stroke
				(width 0.1524)
				(type default)
			)
			(layer "F.SilkS")
		)
		(fp_line
			(start -1.1176 1.4224)
			(end -1.1176 -1.4224)
			(stroke
				(width 0.1524)
				(type default)
			)
			(layer "F.SilkS")
		)
		(fp_line
			(start 1.1176 -1.4224)
			(end 1.1176 1.4224)
			(stroke
				(width 0.1524)
				(type default)
			)
			(layer "F.SilkS")
		)
		(fp_line
			(start 1.1176 1.4224)
			(end -1.1176 1.4224)
			(stroke
				(width 0.1524)
				(type default)
			)
			(layer "F.SilkS")
		)
		(fp_line
			(start 1.2954 1.6002)
			(end 1.2954 0.254)
			(stroke
				(width 0.508)
				(type default)
			)
			(layer "F.SilkS")
		)
		(fp_rect
			(start -0.7493 0.8001)
			(end 0.7493 -0.8001)
			(stroke
				(width 0)
				(type default)
			)
			(fill no)
			(layer "F.CrtYd")
		)
		(fp_poly
			(pts
				(xy -1.3716 1.6764) (xy -1.3716 -1.6764) (xy 1.3716 -1.6764) (xy 1.3716 0.0635) (xy 0.7493 0.0635)
				(xy 0.7493 -0.8001) (xy -0.7493 -0.8001) (xy -0.7493 0.8001) (xy 0.7493 0.8001) (xy 0.7493 0.0762)
				(xy 1.3716 0.0762) (xy 1.3716 1.6764)
			)
			(stroke
				(width 0)
				(type default)
			)
			(fill no)
			(layer "F.CrtYd")
		)
		(fp_rect
			(start -1.3716 1.6764)
			(end 1.3716 -1.6764)
			(stroke
				(width 0)
				(type default)
			)
			(fill no)
			(layer "F.Fab")
		)
		(pad "1" smd rect
			(at 0.50038 -0.73025)
			(size 0.7112 0.8636)
			(layers "F.Cu" "F.Mask" "F.Paste")
			(net "DRV_ACT_0")
		)
		(pad "2" smd rect
			(at -0.50038 -0.73025)
			(size 0.7112 0.8636)
			(layers "F.Cu" "F.Mask" "F.Paste")
			(net "FLT_HDD0")
		)
		(pad "3" smd rect
			(at 0.50038 0.73025)
			(size 0.7112 0.8636)
			(layers "F.Cu" "F.Mask" "F.Paste")
			(net "DRV_ACT_0_N")
		)
		(pad "4" smd rect
			(at -0.50038 0.73025)
			(size 0.7112 0.8636)
			(layers "F.Cu" "F.Mask" "F.Paste")
			(net "FLT_HDD0_N")
		)
	)
	(footprint ""
		(layer "F.Cu")
		(at 446.8622 -261.6454 180)
		(property "Reference" "R319"
			(at 0 0 180)
			(layer "F.SilkS")
			(hide yes)
			(effects
				(font
					(size 1.27 1.27)
				)
			)
		)
		(property "Value" "10KR2F-2-GP"
			(at 0.064008 -3.993896 180)
			(unlocked yes)
			(layer "F.Fab")
			(hide yes)
			(effects
				(font
					(size 1.016 1.016)
					(thickness 0.1524)
				)
			)
		)
		(property "Device Type" "R402H16"
			(at 0.064008 -5.517896 180)
			(unlocked yes)
			(layer "F.Fab")
			(hide yes)
			(effects
				(font
					(size 1.016 1.016)
					(thickness 0.1524)
				)
			)
		)
		(duplicate_pad_numbers_are_jumpers no)
		(fp_line
			(start 0.508 -0.9398)
			(end -0.508 -0.9398)
			(stroke
				(width 0.1524)
				(type default)
			)
			(layer "F.SilkS")
		)
		(fp_line
			(start -0.508 -0.9398)
			(end -0.508 0.9398)
			(stroke
				(width 0.1524)
				(type default)
			)
			(layer "F.SilkS")
		)
		(fp_rect
			(start -0.508 0.9398)
			(end 0.508 -0.9398)
			(stroke
				(width 0)
				(type default)
			)
			(fill no)
			(layer "F.CrtYd")
		)
		(fp_rect
			(start -0.508 0.9398)
			(end 0.508 -0.9398)
			(stroke
				(width 0)
				(type default)
			)
			(fill no)
			(layer "F.Fab")
		)
		(pad "1" smd custom
			(at 0 -0.4445 180)
			(size 0.1397 0.1397)
			(layers "F.Cu" "F.Mask" "F.Paste")
			(net "P3V3_STBY_B")
			(options
				(clearance outline)
				(anchor circle)
			)
			(primitives
				(gr_poly
					(pts
						(arc
							(start -0.1778 -0.2794)
							(mid -0.249642 -0.249642)
							(end -0.2794 -0.1778)
						)
						(arc
							(start -0.2794 0.1778)
							(mid -0.249642 0.249642)
							(end -0.1778 0.2794)
						)
						(arc
							(start 0.1778 0.2794)
							(mid 0.249642 0.249642)
							(end 0.2794 0.1778)
						)
						(arc
							(start 0.2794 -0.1778)
							(mid 0.249642 -0.249642)
							(end 0.1778 -0.2794)
						)
					)
					(width 0)
					(fill yes)
				)
			)
		)
		(pad "2" smd custom
			(at 0 0.4445 180)
			(size 0.1397 0.1397)
			(layers "F.Cu" "F.Mask" "F.Paste")
			(net "HDD_PRSNT_10")
			(options
				(clearance outline)
				(anchor circle)
			)
			(primitives
				(gr_poly
					(pts
						(arc
							(start -0.1778 -0.2794)
							(mid -0.249642 -0.249642)
							(end -0.2794 -0.1778)
						)
						(arc
							(start -0.2794 0.1778)
							(mid -0.249642 0.249642)
							(end -0.1778 0.2794)
						)
						(arc
							(start 0.1778 0.2794)
							(mid 0.249642 0.249642)
							(end 0.2794 0.1778)
						)
						(arc
							(start 0.2794 -0.1778)
							(mid 0.249642 -0.249642)
							(end 0.1778 -0.2794)
						)
					)
					(width 0)
					(fill yes)
				)
			)
		)
	)
	(footprint ""
		(layer "F.Cu")
		(at 14.859 -24.511 -90)
		(property "Reference" "R637"
			(at 0 0 270)
			(layer "F.SilkS")
			(hide yes)
			(effects
				(font
					(size 1.27 1.27)
				)
			)
		)
		(property "Value" "300KR2F-GP"
			(at 0.064008 -3.993896 270)
			(unlocked yes)
			(layer "F.Fab")
			(hide yes)
			(effects
				(font
					(size 1.016 1.016)
					(thickness 0.1524)
				)
			)
		)
		(property "Device Type" "R402H16"
			(at 0.064008 -5.517896 270)
			(unlocked yes)
			(layer "F.Fab")
			(hide yes)
			(effects
				(font
					(size 1.016 1.016)
					(thickness 0.1524)
				)
			)
		)
		(duplicate_pad_numbers_are_jumpers no)
		(fp_line
			(start -0.508 -0.9398)
			(end -0.508 0.9398)
			(stroke
				(width 0.1524)
				(type default)
			)
			(layer "F.SilkS")
		)
		(fp_line
			(start 0.508 -0.9398)
			(end -0.508 -0.9398)
			(stroke
				(width 0.1524)
				(type default)
			)
			(layer "F.SilkS")
		)
		(fp_rect
			(start -0.508 0.9398)
			(end 0.508 -0.9398)
			(stroke
				(width 0)
				(type default)
			)
			(fill no)
			(layer "F.CrtYd")
		)
		(fp_rect
			(start -0.508 0.9398)
			(end 0.508 -0.9398)
			(stroke
				(width 0)
				(type default)
			)
			(fill no)
			(layer "F.Fab")
		)
		(pad "1" smd custom
			(at 0 -0.4445 270)
			(size 0.1397 0.1397)
			(layers "F.Cu" "F.Mask" "F.Paste")
			(net "SW_HDD_N24")
			(options
				(clearance outline)
				(anchor circle)
			)
			(primitives
				(gr_poly
					(pts
						(arc
							(start -0.1778 -0.2794)
							(mid -0.249642 -0.249642)
							(end -0.2794 -0.1778)
						)
						(arc
							(start -0.2794 0.1778)
							(mid -0.249642 0.249642)
							(end -0.1778 0.2794)
						)
						(arc
							(start 0.1778 0.2794)
							(mid 0.249642 0.249642)
							(end 0.2794 0.1778)
						)
						(arc
							(start 0.2794 -0.1778)
							(mid 0.249642 -0.249642)
							(end 0.1778 -0.2794)
						)
					)
					(width 0)
					(fill yes)
				)
			)
		)
		(pad "2" smd custom
			(at 0 0.4445 270)
			(size 0.1397 0.1397)
			(layers "F.Cu" "F.Mask" "F.Paste")
			(net "P12V_B")
			(options
				(clearance outline)
				(anchor circle)
			)
			(primitives
				(gr_poly
					(pts
						(arc
							(start -0.1778 -0.2794)
							(mid -0.249642 -0.249642)
							(end -0.2794 -0.1778)
						)
						(arc
							(start -0.2794 0.1778)
							(mid -0.249642 0.249642)
							(end -0.1778 0.2794)
						)
						(arc
							(start 0.1778 0.2794)
							(mid 0.249642 0.249642)
							(end 0.2794 0.1778)
						)
						(arc
							(start 0.2794 -0.1778)
							(mid 0.249642 -0.249642)
							(end 0.1778 -0.2794)
						)
					)
					(width 0)
					(fill yes)
				)
			)
		)
	)
	(footprint ""
		(layer "F.Cu")
		(at 16.891 -132.588 180)
		(property "Reference" "D12"
			(at 0 0 180)
			(layer "F.SilkS")
			(hide yes)
			(effects
				(font
					(size 1.27 1.27)
				)
			)
		)
		(property "Value" "RB551V30-GP"
			(at 0 -6.7818 180)
			(unlocked yes)
			(layer "F.Fab")
			(hide yes)
			(effects
				(font
					(size 1.016 1.016)
					(thickness 0.1524)
				)
			)
		)
		(property "Device Type" "SOD323AKH38"
			(at 0 -8.6868 180)
			(unlocked yes)
			(layer "F.Fab")
			(hide yes)
			(effects
				(font
					(size 1.016 1.016)
					(thickness 0.1524)
				)
			)
		)
		(duplicate_pad_numbers_are_jumpers no)
		(fp_line
			(start 0.889 2.159)
			(end -0.889 2.159)
			(stroke
				(width 0.1524)
				(type default)
			)
			(layer "F.SilkS")
		)
		(fp_line
			(start 0.889 -1.9304)
			(end 0.889 2.159)
			(stroke
				(width 0.1524)
				(type default)
			)
			(layer "F.SilkS")
		)
		(fp_line
			(start 0.762 2.0574)
			(end -0.762 2.0574)
			(stroke
				(width 0.508)
				(type default)
			)
			(layer "F.SilkS")
		)
		(fp_line
			(start -0.889 2.159)
			(end -0.889 -1.9304)
			(stroke
				(width 0.1524)
				(type default)
			)
			(layer "F.SilkS")
		)
		(fp_line
			(start -0.889 -1.9304)
			(end 0.889 -1.9304)
			(stroke
				(width 0.1524)
				(type default)
			)
			(layer "F.SilkS")
		)
		(fp_rect
			(start -1.016 2.3114)
			(end 1.016 -2.0066)
			(stroke
				(width 0)
				(type default)
			)
			(fill no)
			(layer "F.CrtYd")
		)
		(fp_poly
			(pts
				(xy -1.016 -2.0066) (xy 1.016 -2.0066) (xy 1.016 2.3114) (xy -1.016 2.3114)
			)
			(stroke
				(width 0)
				(type default)
			)
			(fill no)
			(layer "F.Fab")
		)
		(pad "A" smd rect
			(at 0 -1.143 180)
			(size 0.5588 1.016)
			(layers "F.Cu" "F.Mask" "F.Paste")
			(net "SW_HDD_R12")
		)
		(pad "K" smd rect
			(at 0 1.143 180)
			(size 0.5588 1.016)
			(layers "F.Cu" "F.Mask" "F.Paste")
			(net "SW_HDD_N12")
		)
	)
	(footprint ""
		(layer "F.Cu")
		(at 284.000448 -347.541342 180)
		(property "Reference" "R1082"
			(at 0 0 180)
			(layer "F.SilkS")
			(hide yes)
			(effects
				(font
					(size 1.27 1.27)
				)
			)
		)
		(property "Value" "0R2J-2-GP"
			(at 0.064008 -3.993896 180)
			(unlocked yes)
			(layer "F.Fab")
			(hide yes)
			(effects
				(font
					(size 1.016 1.016)
					(thickness 0.1524)
				)
			)
		)
		(property "Device Type" "R402H16"
			(at 0.064008 -5.517896 180)
			(unlocked yes)
			(layer "F.Fab")
			(hide yes)
			(effects
				(font
					(size 1.016 1.016)
					(thickness 0.1524)
				)
			)
		)
		(duplicate_pad_numbers_are_jumpers no)
		(fp_line
			(start 0.508 -0.9398)
			(end -0.508 -0.9398)
			(stroke
				(width 0.1524)
				(type default)
			)
			(layer "F.SilkS")
		)
		(fp_line
			(start -0.508 -0.9398)
			(end -0.508 0.9398)
			(stroke
				(width 0.1524)
				(type default)
			)
			(layer "F.SilkS")
		)
		(fp_rect
			(start -0.508 0.9398)
			(end 0.508 -0.9398)
			(stroke
				(width 0)
				(type default)
			)
			(fill no)
			(layer "F.CrtYd")
		)
		(fp_rect
			(start -0.508 0.9398)
			(end 0.508 -0.9398)
			(stroke
				(width 0)
				(type default)
			)
			(fill no)
			(layer "F.Fab")
		)
		(pad "1" smd custom
			(at 0 -0.4445 180)
			(size 0.1397 0.1397)
			(layers "F.Cu" "F.Mask" "F.Paste")
			(net "GND")
			(options
				(clearance outline)
				(anchor circle)
			)
			(primitives
				(gr_poly
					(pts
						(arc
							(start -0.1778 -0.2794)
							(mid -0.249642 -0.249642)
							(end -0.2794 -0.1778)
						)
						(arc
							(start -0.2794 0.1778)
							(mid -0.249642 0.249642)
							(end -0.1778 0.2794)
						)
						(arc
							(start 0.1778 0.2794)
							(mid 0.249642 0.249642)
							(end 0.2794 0.1778)
						)
						(arc
							(start 0.2794 -0.1778)
							(mid 0.249642 -0.249642)
							(end 0.1778 -0.2794)
						)
					)
					(width 0)
					(fill yes)
				)
			)
		)
		(pad "2" smd custom
			(at 0 0.4445 180)
			(size 0.1397 0.1397)
			(layers "F.Cu" "F.Mask" "F.Paste")
			(net "MAX31790_B_SPIN_ST")
			(options
				(clearance outline)
				(anchor circle)
			)
			(primitives
				(gr_poly
					(pts
						(arc
							(start -0.1778 -0.2794)
							(mid -0.249642 -0.249642)
							(end -0.2794 -0.1778)
						)
						(arc
							(start -0.2794 0.1778)
							(mid -0.249642 0.249642)
							(end -0.1778 0.2794)
						)
						(arc
							(start 0.1778 0.2794)
							(mid 0.249642 0.249642)
							(end 0.2794 0.1778)
						)
						(arc
							(start 0.2794 -0.1778)
							(mid 0.249642 -0.249642)
							(end 0.1778 -0.2794)
						)
					)
					(width 0)
					(fill yes)
				)
			)
		)
	)
)
